# BASEBOARD_FAB2 (Tioga Pass) — schematic netlist excerpt (pin names and nets, part order shuffled) for the footprints in the layout excerpt that follows; sources: Cadence DE-HDL packaged netlist, KiCad conversion of Wiwynn_Tioga_Pass_MB.brd

C4E5  CAP  0.22UF 16V 10% X7R  pkg 0402  page 202 : A = P5V_STBY ; B = GND
R4W3  RES  3.3K 5% CHIP  pkg 0402  page 102 : A = P3V3_DB1200 ; B = SMB_HOST_STBY_LVC3_SDA_R2
R8C21  RES  100.0 1% CHIP  pkg 0402  page 120 : A = A_RCOMP_3P3 ; B = GND

(kicad_pcb
	(version 20260206)
	(generator "pcbnew")
	(generator_version "10.0")
	(general
		(thickness 1.6)
		(legacy_teardrops no)
	)
	(paper "A4")
	(title_block
		(title "Wiwynn_Tioga_Pass_MB.brd")
		(comment 1 "Tioga Pass / footprints 2298-2300 of 4770")
	)
	(layers
		(0 "F.Cu" signal "TOP")
		(4 "In1.Cu" signal "L2GND")
		(6 "In2.Cu" signal "L3")
		(8 "In3.Cu" signal "L4GND")
		(10 "In4.Cu" signal "L5")
		(12 "In5.Cu" signal "L6GND")
		(14 "In6.Cu" signal "L7VCC")
		(16 "In7.Cu" signal "L8VCC")
		(18 "In8.Cu" signal "L9GND")
		(20 "In9.Cu" signal "L10")
		(22 "In10.Cu" signal "L11GND")
		(24 "In11.Cu" signal "L12")
		(26 "In12.Cu" signal "L13GND")
		(2 "B.Cu" signal "BOTTOM")
		(9 "F.Adhes" user "F.Adhesive")
		(11 "B.Adhes" user "B.Adhesive")
		(13 "F.Paste" user "Package Geometry/Pastemask Top")
		(15 "B.Paste" user "Package Geometry/Pastemask Bottom")
		(5 "F.SilkS" user "Ref Des/Silkscreen Top")
		(7 "B.SilkS" user "Ref Des/Silkscreen Bottom")
		(1 "F.Mask" user "Board Geometry/Soldermask Top")
		(3 "B.Mask" user "Board Geometry/Soldermask Bottom")
		(17 "Dwgs.User" user "User.Drawings")
		(19 "Cmts.User" user "User.Comments")
		(21 "Eco1.User" user "User.Eco1")
		(23 "Eco2.User" user "User.Eco2")
		(25 "Edge.Cuts" user "Board Geometry/Outline")
		(27 "Margin" user)
		(31 "F.CrtYd" user "Package Geometry/Place Bound Top")
		(29 "B.CrtYd" user "Package Geometry/Place Bound Bottom")
		(35 "F.Fab" user "Ref Des/Assembly Top")
		(33 "B.Fab" user "Ref Des/Assembly Bottom")
	)
	(footprint ""
		(layer "F.Cu")
		(at 405.8285 -105.664 90)
		(property "Reference" "R8C21"
			(at 0 0 90)
			(layer "F.SilkS")
			(hide yes)
			(effects
				(font
					(size 1.27 1.27)
				)
			)
		)
		(property "Value" ""
			(at 0 0 90)
			(layer "F.Fab")
			(effects
				(font
					(size 1.27 1.27)
				)
			)
		)
		(duplicate_pad_numbers_are_jumpers no)
		(fp_poly
			(pts
				(xy -0.2794 -0.1016) (xy 0.2794 -0.1016) (xy 0.2794 0.9906) (xy -0.2794 0.9906)
			)
			(stroke
				(width 0)
				(type default)
			)
			(fill no)
			(layer "F.CrtYd")
		)
		(fp_line
			(start 0.2794 -0.1016)
			(end -0.2794 -0.1016)
			(stroke
				(width 0.1)
				(type default)
			)
			(layer "F.Fab")
		)
		(fp_line
			(start -0.2794 -0.1016)
			(end -0.2794 0.9906)
			(stroke
				(width 0.1)
				(type default)
			)
			(layer "F.Fab")
		)
		(fp_line
			(start 0.2794 0.9906)
			(end 0.2794 -0.1016)
			(stroke
				(width 0.1)
				(type default)
			)
			(layer "F.Fab")
		)
		(fp_line
			(start -0.2794 0.9906)
			(end 0.2794 0.9906)
			(stroke
				(width 0.1)
				(type default)
			)
			(layer "F.Fab")
		)
		(pad "1" smd rect
			(at 0 0 90)
			(size 0.508 0.508)
			(layers "F.Cu" "F.Mask" "F.Paste")
			(net "A_RCOMP_3P3")
		)
		(pad "2" smd rect
			(at 0 0.889 90)
			(size 0.508 0.508)
			(layers "F.Cu" "F.Mask" "F.Paste")
			(net "GND")
		)
		(zone
			(layer "F.Cu")
			(hatch none 0.5)
			(connect_pads
				(clearance 0)
			)
			(min_thickness 0.25)
			(keepout
				(tracks allowed)
				(vias not_allowed)
				(pads allowed)
				(copperpour not_allowed)
				(footprints allowed)
			)
			(placement
				(enabled no)
				(sheetname "")
			)
			(fill
				(thermal_gap 0.5)
				(thermal_bridge_width 0.5)
				(island_removal_mode 0)
			)
			(polygon
				(pts
					(xy 406.0825 -105.41) (xy 406.0825 -105.918) (xy 406.4635 -105.918) (xy 406.4635 -105.41)
				)
			)
		)
		(zone
			(layer "F.Cu")
			(hatch none 0.5)
			(connect_pads
				(clearance 0)
			)
			(min_thickness 0.25)
			(keepout
				(tracks not_allowed)
				(vias allowed)
				(pads allowed)
				(copperpour not_allowed)
				(footprints allowed)
			)
			(placement
				(enabled no)
				(sheetname "")
			)
			(fill
				(thermal_gap 0.5)
				(thermal_bridge_width 0.5)
				(island_removal_mode 0)
			)
			(polygon
				(pts
					(xy 406.4635 -105.41) (xy 406.4635 -105.918) (xy 406.0825 -105.918) (xy 406.0825 -105.41)
				)
			)
		)
	)
	(footprint ""
		(layer "F.Cu")
		(at 198.178928 -53.221382 90)
		(property "Reference" "C4E5"
			(at 0 0 90)
			(layer "F.SilkS")
			(hide yes)
			(effects
				(font
					(size 1.27 1.27)
				)
			)
		)
		(property "Value" ""
			(at 0 0 90)
			(layer "F.Fab")
			(effects
				(font
					(size 1.27 1.27)
				)
			)
		)
		(duplicate_pad_numbers_are_jumpers no)
		(fp_rect
			(start 0.3048 0.9906)
			(end -0.3048 -0.1016)
			(stroke
				(width 0)
				(type default)
			)
			(fill no)
			(layer "F.CrtYd")
		)
		(fp_line
			(start 0.3048 -0.1016)
			(end -0.3048 -0.1016)
			(stroke
				(width 0.1)
				(type default)
			)
			(layer "F.Fab")
		)
		(fp_line
			(start -0.3048 -0.1016)
			(end -0.3048 0.9906)
			(stroke
				(width 0.1)
				(type default)
			)
			(layer "F.Fab")
		)
		(fp_line
			(start 0.3048 0.9906)
			(end 0.3048 -0.1016)
			(stroke
				(width 0.1)
				(type default)
			)
			(layer "F.Fab")
		)
		(fp_line
			(start -0.3048 0.9906)
			(end 0.3048 0.9906)
			(stroke
				(width 0.1)
				(type default)
			)
			(layer "F.Fab")
		)
		(pad "1" smd rect
			(at 0 0 90)
			(size 0.508 0.508)
			(layers "F.Cu" "F.Mask" "F.Paste")
			(net "P5V_STBY")
		)
		(pad "2" smd rect
			(at 0 0.889 90)
			(size 0.508 0.508)
			(layers "F.Cu" "F.Mask" "F.Paste")
			(net "GND")
		)
		(zone
			(layer "F.Cu")
			(hatch none 0.5)
			(connect_pads
				(clearance 0)
			)
			(min_thickness 0.25)
			(keepout
				(tracks allowed)
				(vias not_allowed)
				(pads allowed)
				(copperpour not_allowed)
				(footprints allowed)
			)
			(placement
				(enabled no)
				(sheetname "")
			)
			(fill
				(thermal_gap 0.5)
				(thermal_bridge_width 0.5)
				(island_removal_mode 0)
			)
			(polygon
				(pts
					(xy 198.813928 -53.475382) (xy 198.432928 -53.475382) (xy 198.432928 -52.967382) (xy 198.813928 -52.967382)
				)
			)
		)
		(zone
			(layer "F.Cu")
			(hatch none 0.5)
			(connect_pads
				(clearance 0)
			)
			(min_thickness 0.25)
			(keepout
				(tracks not_allowed)
				(vias allowed)
				(pads allowed)
				(copperpour not_allowed)
				(footprints allowed)
			)
			(placement
				(enabled no)
				(sheetname "")
			)
			(fill
				(thermal_gap 0.5)
				(thermal_bridge_width 0.5)
				(island_removal_mode 0)
			)
			(polygon
				(pts
					(xy 198.813928 -53.475382) (xy 198.432928 -53.475382) (xy 198.432928 -52.967382) (xy 198.813928 -52.967382)
				)
			)
		)
	)
	(footprint ""
		(layer "F.Cu")
		(at 171.989496 -74.972672 90)
		(property "Reference" "R4W3"
			(at -0.8382 -0.67818 90)
			(unlocked yes)
			(layer "F.SilkS")
			(effects
				(font
					(size 0.4064 0.254)
					(thickness 0.1524)
				)
				(justify left)
			)
		)
		(property "Value" ""
			(at 0 0 90)
			(layer "F.Fab")
			(effects
				(font
					(size 1.27 1.27)
				)
			)
		)
		(duplicate_pad_numbers_are_jumpers no)
		(fp_poly
			(pts
				(xy -0.2794 -0.1016) (xy 0.2794 -0.1016) (xy 0.2794 0.9906) (xy -0.2794 0.9906)
			)
			(stroke
				(width 0)
				(type default)
			)
			(fill no)
			(layer "F.CrtYd")
		)
		(fp_line
			(start 0.2794 -0.1016)
			(end -0.2794 -0.1016)
			(stroke
				(width 0.1)
				(type default)
			)
			(layer "F.Fab")
		)
		(fp_line
			(start -0.2794 -0.1016)
			(end -0.2794 0.9906)
			(stroke
				(width 0.1)
				(type default)
			)
			(layer "F.Fab")
		)
		(fp_line
			(start 0.2794 0.9906)
			(end 0.2794 -0.1016)
			(stroke
				(width 0.1)
				(type default)
			)
			(layer "F.Fab")
		)
		(fp_line
			(start -0.2794 0.9906)
			(end 0.2794 0.9906)
			(stroke
				(width 0.1)
				(type default)
			)
			(layer "F.Fab")
		)
		(pad "1" smd rect
			(at 0 0 90)
			(size 0.508 0.508)
			(layers "F.Cu" "F.Mask" "F.Paste")
			(net "P3V3_DB1200")
		)
		(pad "2" smd rect
			(at 0 0.889 90)
			(size 0.508 0.508)
			(layers "F.Cu" "F.Mask" "F.Paste")
			(net "SMB_HOST_STBY_LVC3_SDA_R2")
		)
		(zone
			(layer "F.Cu")
			(hatch none 0.5)
			(connect_pads
				(clearance 0)
			)
			(min_thickness 0.25)
			(keepout
				(tracks allowed)
				(vias not_allowed)
				(pads allowed)
				(copperpour not_allowed)
				(footprints allowed)
			)
			(placement
				(enabled no)
				(sheetname "")
			)
			(fill
				(thermal_gap 0.5)
				(thermal_bridge_width 0.5)
				(island_removal_mode 0)
			)
			(polygon
				(pts
					(xy 172.243496 -74.718672) (xy 172.243496 -75.226672) (xy 172.624496 -75.226672) (xy 172.624496 -74.718672)
				)
			)
		)
		(zone
			(layer "F.Cu")
			(hatch none 0.5)
			(connect_pads
				(clearance 0)
			)
			(min_thickness 0.25)
			(keepout
				(tracks not_allowed)
				(vias allowed)
				(pads allowed)
				(copperpour not_allowed)
				(footprints allowed)
			)
			(placement
				(enabled no)
				(sheetname "")
			)
			(fill
				(thermal_gap 0.5)
				(thermal_bridge_width 0.5)
				(island_removal_mode 0)
			)
			(polygon
				(pts
					(xy 172.624496 -74.718672) (xy 172.624496 -75.226672) (xy 172.243496 -75.226672) (xy 172.243496 -74.718672)
				)
			)
		)
	)
)
